(kicad_pcb
	(version 20260206)
	(generator "pcbnew")
	(generator_version "10.0")
	(general
		(thickness 1.6)
		(legacy_teardrops no)
	)
	(paper "A4")
	(title_block
		(title "Bryce Canyon_R.DPB_16317-1_OCP.brd")
		(comment 1 "Bryce Canyon / footprints 506-513 of 2099")
	)
	(layers
		(0 "F.Cu" signal "TOP")
		(4 "In1.Cu" signal "L2GND")
		(6 "In2.Cu" signal "L3")
		(8 "In3.Cu" signal "L4VCC")
		(10 "In4.Cu" signal "L5VCC")
		(12 "In5.Cu" signal "L6")
		(14 "In6.Cu" signal "L7GND")
		(2 "B.Cu" signal "BOTTOM")
		(9 "F.Adhes" user "F.Adhesive")
		(11 "B.Adhes" user "B.Adhesive")
		(13 "F.Paste" user "Package Geometry/Pastemask Top")
		(15 "B.Paste" user "Package Geometry/Pastemask Bottom")
		(5 "F.SilkS" user "Ref Des/Silkscreen Top")
		(7 "B.SilkS" user "Ref Des/Silkscreen Bottom")
		(1 "F.Mask" user "Board Geometry/Soldermask Top")
		(3 "B.Mask" user "Board Geometry/Soldermask Bottom")
		(17 "Dwgs.User" user "User.Drawings")
		(19 "Cmts.User" user "User.Comments")
		(21 "Eco1.User" user "User.Eco1")
		(23 "Eco2.User" user "User.Eco2")
		(25 "Edge.Cuts" user "Board Geometry/Outline")
		(27 "Margin" user)
		(31 "F.CrtYd" user "Package Geometry/Place Bound Top")
		(29 "B.CrtYd" user "Package Geometry/Place Bound Bottom")
		(35 "F.Fab" user "Ref Des/Assembly Top")
		(33 "B.Fab" user "Ref Des/Assembly Bottom")
	)
	(footprint ""
		(layer "F.Cu")
		(at 248.285 -308.102 -90)
		(property "Reference" "R1167"
			(at 0 0 270)
			(layer "F.SilkS")
			(hide yes)
			(effects
				(font
					(size 1.27 1.27)
				)
			)
		)
		(property "Value" "0R2J-2-GP"
			(at 0.064008 -3.993896 270)
			(unlocked yes)
			(layer "F.Fab")
			(hide yes)
			(effects
				(font
					(size 1.016 1.016)
					(thickness 0.1524)
				)
			)
		)
		(property "Device Type" "R402H16"
			(at 0.064008 -5.517896 270)
			(unlocked yes)
			(layer "F.Fab")
			(hide yes)
			(effects
				(font
					(size 1.016 1.016)
					(thickness 0.1524)
				)
			)
		)
		(duplicate_pad_numbers_are_jumpers no)
		(fp_line
			(start -0.508 -0.9398)
			(end -0.508 0.9398)
			(stroke
				(width 0.1524)
				(type default)
			)
			(layer "F.SilkS")
		)
		(fp_line
			(start 0.508 -0.9398)
			(end -0.508 -0.9398)
			(stroke
				(width 0.1524)
				(type default)
			)
			(layer "F.SilkS")
		)
		(fp_rect
			(start -0.508 0.9398)
			(end 0.508 -0.9398)
			(stroke
				(width 0)
				(type default)
			)
			(fill no)
			(layer "F.CrtYd")
		)
		(fp_rect
			(start -0.508 0.9398)
			(end 0.508 -0.9398)
			(stroke
				(width 0)
				(type default)
			)
			(fill no)
			(layer "F.Fab")
		)
		(pad "1" smd custom
			(at 0 -0.4445 270)
			(size 0.1397 0.1397)
			(layers "F.Cu" "F.Mask" "F.Paste")
			(net "P3V3_STBY_A")
			(options
				(clearance outline)
				(anchor circle)
			)
			(primitives
				(gr_poly
					(pts
						(arc
							(start -0.1778 -0.2794)
							(mid -0.249642 -0.249642)
							(end -0.2794 -0.1778)
						)
						(arc
							(start -0.2794 0.1778)
							(mid -0.249642 0.249642)
							(end -0.1778 0.2794)
						)
						(arc
							(start 0.1778 0.2794)
							(mid 0.249642 0.249642)
							(end 0.2794 0.1778)
						)
						(arc
							(start 0.2794 -0.1778)
							(mid 0.249642 -0.249642)
							(end 0.1778 -0.2794)
						)
					)
					(width 0)
					(fill yes)
				)
			)
		)
		(pad "2" smd custom
			(at 0 0.4445 270)
			(size 0.1397 0.1397)
			(layers "F.Cu" "F.Mask" "F.Paste")
			(net "MAX31790_A_PWM_ST0")
			(options
				(clearance outline)
				(anchor circle)
			)
			(primitives
				(gr_poly
					(pts
						(arc
							(start -0.1778 -0.2794)
							(mid -0.249642 -0.249642)
							(end -0.2794 -0.1778)
						)
						(arc
							(start -0.2794 0.1778)
							(mid -0.249642 0.249642)
							(end -0.1778 0.2794)
						)
						(arc
							(start 0.1778 0.2794)
							(mid 0.249642 0.249642)
							(end 0.2794 0.1778)
						)
						(arc
							(start 0.2794 -0.1778)
							(mid 0.249642 -0.249642)
							(end 0.1778 -0.2794)
						)
					)
					(width 0)
					(fill yes)
				)
			)
		)
	)
	(footprint ""
		(layer "F.Cu")
		(at 473.0242 -7.1882 180)
		(property "Reference" "R891"
			(at 0 0 180)
			(layer "F.SilkS")
			(hide yes)
			(effects
				(font
					(size 1.27 1.27)
				)
			)
		)
		(property "Value" "200KR2F-L-GP"
			(at 0.064008 -3.993896 180)
			(unlocked yes)
			(layer "F.Fab")
			(hide yes)
			(effects
				(font
					(size 1.016 1.016)
					(thickness 0.1524)
				)
			)
		)
		(property "Device Type" "R402H16"
			(at 0.064008 -5.517896 180)
			(unlocked yes)
			(layer "F.Fab")
			(hide yes)
			(effects
				(font
					(size 1.016 1.016)
					(thickness 0.1524)
				)
			)
		)
		(duplicate_pad_numbers_are_jumpers no)
		(fp_line
			(start 0.508 -0.9398)
			(end -0.508 -0.9398)
			(stroke
				(width 0.1524)
				(type default)
			)
			(layer "F.SilkS")
		)
		(fp_line
			(start -0.508 -0.9398)
			(end -0.508 0.9398)
			(stroke
				(width 0.1524)
				(type default)
			)
			(layer "F.SilkS")
		)
		(fp_rect
			(start -0.508 0.9398)
			(end 0.508 -0.9398)
			(stroke
				(width 0)
				(type default)
			)
			(fill no)
			(layer "F.CrtYd")
		)
		(fp_rect
			(start -0.508 0.9398)
			(end 0.508 -0.9398)
			(stroke
				(width 0)
				(type default)
			)
			(fill no)
			(layer "F.Fab")
		)
		(pad "1" smd custom
			(at 0 -0.4445 180)
			(size 0.1397 0.1397)
			(layers "F.Cu" "F.Mask" "F.Paste")
			(net "SW_HDD_R35")
			(options
				(clearance outline)
				(anchor circle)
			)
			(primitives
				(gr_poly
					(pts
						(arc
							(start -0.1778 -0.2794)
							(mid -0.249642 -0.249642)
							(end -0.2794 -0.1778)
						)
						(arc
							(start -0.2794 0.1778)
							(mid -0.249642 0.249642)
							(end -0.1778 0.2794)
						)
						(arc
							(start 0.1778 0.2794)
							(mid 0.249642 0.249642)
							(end 0.2794 0.1778)
						)
						(arc
							(start 0.2794 -0.1778)
							(mid 0.249642 -0.249642)
							(end 0.1778 -0.2794)
						)
					)
					(width 0)
					(fill yes)
				)
			)
		)
		(pad "2" smd custom
			(at 0 0.4445 180)
			(size 0.1397 0.1397)
			(layers "F.Cu" "F.Mask" "F.Paste")
			(net "SW_HDD_N35")
			(options
				(clearance outline)
				(anchor circle)
			)
			(primitives
				(gr_poly
					(pts
						(arc
							(start -0.1778 -0.2794)
							(mid -0.249642 -0.249642)
							(end -0.2794 -0.1778)
						)
						(arc
							(start -0.2794 0.1778)
							(mid -0.249642 0.249642)
							(end -0.1778 0.2794)
						)
						(arc
							(start 0.1778 0.2794)
							(mid 0.249642 0.249642)
							(end 0.2794 0.1778)
						)
						(arc
							(start 0.2794 -0.1778)
							(mid 0.249642 -0.249642)
							(end 0.1778 -0.2794)
						)
					)
					(width 0)
					(fill yes)
				)
			)
		)
	)
	(footprint ""
		(layer "F.Cu")
		(at 241.386106 -352.755962 180)
		(property "Reference" "C563"
			(at 0 0 180)
			(layer "F.SilkS")
			(hide yes)
			(effects
				(font
					(size 1.27 1.27)
				)
			)
		)
		(property "Value" "SCD1U25V2KX-2-GP"
			(at 1.1811 -2.7051 180)
			(unlocked yes)
			(layer "F.Fab")
			(hide yes)
			(effects
				(font
					(size 1.016 1.016)
					(thickness 0.1524)
				)
			)
		)
		(property "Device Type" "C402H22"
			(at 1.1811 -4.2291 180)
			(unlocked yes)
			(layer "F.Fab")
			(hide yes)
			(effects
				(font
					(size 1.016 1.016)
					(thickness 0.1524)
				)
			)
		)
		(duplicate_pad_numbers_are_jumpers no)
		(fp_rect
			(start -0.4318 0.9525)
			(end 0.4318 -0.9525)
			(stroke
				(width 0)
				(type default)
			)
			(fill no)
			(layer "F.CrtYd")
		)
		(fp_rect
			(start -0.4318 0.9525)
			(end 0.4318 -0.9525)
			(stroke
				(width 0)
				(type default)
			)
			(fill no)
			(layer "F.Fab")
		)
		(pad "1" smd custom
			(at 0 -0.4445 180)
			(size 0.1524 0.1524)
			(layers "F.Cu" "F.Mask" "F.Paste")
			(net "P12V_IN")
			(options
				(clearance outline)
				(anchor circle)
			)
			(primitives
				(gr_poly
					(pts
						(arc
							(start 0.3048 -0.2032)
							(mid 0.275042 -0.275042)
							(end 0.2032 -0.3048)
						)
						(arc
							(start -0.2032 -0.3048)
							(mid -0.275042 -0.275042)
							(end -0.3048 -0.2032)
						)
						(arc
							(start -0.3048 0.2032)
							(mid -0.275042 0.275042)
							(end -0.2032 0.3048)
						)
						(arc
							(start 0.2032 0.3048)
							(mid 0.275042 0.275042)
							(end 0.3048 0.2032)
						)
					)
					(width 0)
					(fill yes)
				)
			)
		)
		(pad "2" smd custom
			(at 0 0.4445 180)
			(size 0.1524 0.1524)
			(layers "F.Cu" "F.Mask" "F.Paste")
			(net "GND")
			(options
				(clearance outline)
				(anchor circle)
			)
			(primitives
				(gr_poly
					(pts
						(arc
							(start 0.3048 -0.2032)
							(mid 0.275042 -0.275042)
							(end 0.2032 -0.3048)
						)
						(arc
							(start -0.2032 -0.3048)
							(mid -0.275042 -0.275042)
							(end -0.3048 -0.2032)
						)
						(arc
							(start -0.3048 0.2032)
							(mid -0.275042 0.275042)
							(end -0.2032 0.3048)
						)
						(arc
							(start 0.2032 0.3048)
							(mid 0.275042 0.275042)
							(end 0.3048 0.2032)
						)
					)
					(width 0)
					(fill yes)
				)
			)
		)
	)
	(footprint ""
		(layer "F.Cu")
		(at 14.859 -255.524 90)
		(property "Reference" "C507"
			(at 0 0 90)
			(layer "F.SilkS")
			(hide yes)
			(effects
				(font
					(size 1.27 1.27)
				)
			)
		)
		(property "Value" "SCD033U25V2KX-GP"
			(at 1.1811 -2.7051 90)
			(unlocked yes)
			(layer "F.Fab")
			(hide yes)
			(effects
				(font
					(size 1.016 1.016)
					(thickness 0.1524)
				)
			)
		)
		(property "Device Type" "C402H22"
			(at 1.1811 -4.2291 90)
			(unlocked yes)
			(layer "F.Fab")
			(hide yes)
			(effects
				(font
					(size 1.016 1.016)
					(thickness 0.1524)
				)
			)
		)
		(duplicate_pad_numbers_are_jumpers no)
		(fp_rect
			(start -0.4318 0.9525)
			(end 0.4318 -0.9525)
			(stroke
				(width 0)
				(type default)
			)
			(fill no)
			(layer "F.CrtYd")
		)
		(fp_rect
			(start -0.4318 0.9525)
			(end 0.4318 -0.9525)
			(stroke
				(width 0)
				(type default)
			)
			(fill no)
			(layer "F.Fab")
		)
		(pad "1" smd custom
			(at 0 -0.4445 90)
			(size 0.1524 0.1524)
			(layers "F.Cu" "F.Mask" "F.Paste")
			(net "P12V_B")
			(options
				(clearance outline)
				(anchor circle)
			)
			(primitives
				(gr_poly
					(pts
						(arc
							(start 0.3048 -0.2032)
							(mid 0.275042 -0.275042)
							(end 0.2032 -0.3048)
						)
						(arc
							(start -0.2032 -0.3048)
							(mid -0.275042 -0.275042)
							(end -0.3048 -0.2032)
						)
						(arc
							(start -0.3048 0.2032)
							(mid -0.275042 0.275042)
							(end -0.2032 0.3048)
						)
						(arc
							(start 0.2032 0.3048)
							(mid 0.275042 0.275042)
							(end 0.3048 0.2032)
						)
					)
					(width 0)
					(fill yes)
				)
			)
		)
		(pad "2" smd custom
			(at 0 0.4445 90)
			(size 0.1524 0.1524)
			(layers "F.Cu" "F.Mask" "F.Paste")
			(net "SW_HDD_N0")
			(options
				(clearance outline)
				(anchor circle)
			)
			(primitives
				(gr_poly
					(pts
						(arc
							(start 0.3048 -0.2032)
							(mid 0.275042 -0.275042)
							(end 0.2032 -0.3048)
						)
						(arc
							(start -0.2032 -0.3048)
							(mid -0.275042 -0.275042)
							(end -0.3048 -0.2032)
						)
						(arc
							(start -0.3048 0.2032)
							(mid -0.275042 0.275042)
							(end -0.2032 0.3048)
						)
						(arc
							(start 0.2032 0.3048)
							(mid 0.275042 0.275042)
							(end 0.3048 0.2032)
						)
					)
					(width 0)
					(fill yes)
				)
			)
		)
	)
	(footprint ""
		(layer "F.Cu")
		(at 192.035684 -244.990874 90)
		(property "Reference" "VIA11"
			(at 0 0 90)
			(layer "F.SilkS")
			(hide yes)
			(effects
				(font
					(size 1.27 1.27)
				)
			)
		)
		(property "Value" "100OHM-8L-2D36MM-L18-GP"
			(at 3.8989 0.5715 90)
			(unlocked yes)
			(layer "F.Fab")
			(hide yes)
			(effects
				(font
					(size 1.016 1.016)
					(thickness 0.1524)
				)
			)
		)
		(property "Device Type" "VIA-PCIE-4P-414097"
			(at 3.8989 -0.9525 90)
			(unlocked yes)
			(layer "F.Fab")
			(hide yes)
			(effects
				(font
					(size 1.016 1.016)
					(thickness 0.1524)
				)
			)
		)
		(duplicate_pad_numbers_are_jumpers no)
		(fp_rect
			(start -2.0701 0.4826)
			(end 2.0701 -0.4826)
			(stroke
				(width 0)
				(type default)
			)
			(fill no)
			(layer "F.CrtYd")
		)
		(fp_rect
			(start -2.0701 0.4826)
			(end 2.0701 -0.4826)
			(stroke
				(width 0)
				(type default)
			)
			(fill no)
			(layer "F.Fab")
		)
		(pad "1" thru_hole circle
			(at -1.5875 0 90)
			(size 0.508 0.508)
			(drill 0.254)
			(layers "*.Cu" "*.Mask")
			(remove_unused_layers no)
			(net "GND")
			(clearance 0.2286)
			(thermal_gap 0.2286)
		)
		(pad "2" thru_hole circle
			(at -0.5715 0 90)
			(size 0.508 0.508)
			(drill 0.254)
			(layers "*.Cu" "*.Mask")
			(remove_unused_layers no)
			(net "PHY_SCC_B_TO_DRV_B_5_DP")
			(clearance 0.2286)
			(thermal_gap 0.2286)
		)
		(pad "3" thru_hole circle
			(at 0.5715 0 90)
			(size 0.508 0.508)
			(drill 0.254)
			(layers "*.Cu" "*.Mask")
			(remove_unused_layers no)
			(net "PHY_SCC_B_TO_DRV_B_5_DN")
			(clearance 0.2286)
			(thermal_gap 0.2286)
		)
		(pad "4" thru_hole circle
			(at 1.5875 0 90)
			(size 0.508 0.508)
			(drill 0.254)
			(layers "*.Cu" "*.Mask")
			(remove_unused_layers no)
			(net "GND")
			(clearance 0.2286)
			(thermal_gap 0.2286)
		)
	)
	(footprint ""
		(layer "F.Cu")
		(at 298.6532 -332.9686 180)
		(property "Reference" "C21"
			(at 0 0 180)
			(layer "F.SilkS")
			(hide yes)
			(effects
				(font
					(size 1.27 1.27)
				)
			)
		)
		(property "Value" "SCD1U16V2KX-3GP"
			(at 1.1811 -2.7051 180)
			(unlocked yes)
			(layer "F.Fab")
			(hide yes)
			(effects
				(font
					(size 1.016 1.016)
					(thickness 0.1524)
				)
			)
		)
		(property "Device Type" "C402H22"
			(at 1.1811 -4.2291 180)
			(unlocked yes)
			(layer "F.Fab")
			(hide yes)
			(effects
				(font
					(size 1.016 1.016)
					(thickness 0.1524)
				)
			)
		)
		(duplicate_pad_numbers_are_jumpers no)
		(fp_rect
			(start -0.4318 0.9525)
			(end 0.4318 -0.9525)
			(stroke
				(width 0)
				(type default)
			)
			(fill no)
			(layer "F.CrtYd")
		)
		(fp_rect
			(start -0.4318 0.9525)
			(end 0.4318 -0.9525)
			(stroke
				(width 0)
				(type default)
			)
			(fill no)
			(layer "F.Fab")
		)
		(pad "1" smd custom
			(at 0 -0.4445 180)
			(size 0.1524 0.1524)
			(layers "F.Cu" "F.Mask" "F.Paste")
			(net "P3V3_IN")
			(options
				(clearance outline)
				(anchor circle)
			)
			(primitives
				(gr_poly
					(pts
						(arc
							(start 0.3048 -0.2032)
							(mid 0.275042 -0.275042)
							(end 0.2032 -0.3048)
						)
						(arc
							(start -0.2032 -0.3048)
							(mid -0.275042 -0.275042)
							(end -0.3048 -0.2032)
						)
						(arc
							(start -0.3048 0.2032)
							(mid -0.275042 0.275042)
							(end -0.2032 0.3048)
						)
						(arc
							(start 0.2032 0.3048)
							(mid 0.275042 0.275042)
							(end 0.3048 0.2032)
						)
					)
					(width 0)
					(fill yes)
				)
			)
		)
		(pad "2" smd custom
			(at 0 0.4445 180)
			(size 0.1524 0.1524)
			(layers "F.Cu" "F.Mask" "F.Paste")
			(net "GND")
			(options
				(clearance outline)
				(anchor circle)
			)
			(primitives
				(gr_poly
					(pts
						(arc
							(start 0.3048 -0.2032)
							(mid 0.275042 -0.275042)
							(end 0.2032 -0.3048)
						)
						(arc
							(start -0.2032 -0.3048)
							(mid -0.275042 -0.275042)
							(end -0.3048 -0.2032)
						)
						(arc
							(start -0.3048 0.2032)
							(mid -0.275042 0.275042)
							(end -0.2032 0.3048)
						)
						(arc
							(start 0.2032 0.3048)
							(mid 0.275042 0.275042)
							(end 0.3048 0.2032)
						)
					)
					(width 0)
					(fill yes)
				)
			)
		)
	)
	(footprint ""
		(layer "F.Cu")
		(at 426.1866 -250.5202 -90)
		(property "Reference" "C155"
			(at 0 0 270)
			(layer "F.SilkS")
			(hide yes)
			(effects
				(font
					(size 1.27 1.27)
				)
			)
		)
		(property "Value" "SCD033U25V2KX-GP"
			(at 1.1811 -2.7051 270)
			(unlocked yes)
			(layer "F.Fab")
			(hide yes)
			(effects
				(font
					(size 1.016 1.016)
					(thickness 0.1524)
				)
			)
		)
		(property "Device Type" "C402H22"
			(at 1.1811 -4.2291 270)
			(unlocked yes)
			(layer "F.Fab")
			(hide yes)
			(effects
				(font
					(size 1.016 1.016)
					(thickness 0.1524)
				)
			)
		)
		(duplicate_pad_numbers_are_jumpers no)
		(fp_rect
			(start -0.4318 0.9525)
			(end 0.4318 -0.9525)
			(stroke
				(width 0)
				(type default)
			)
			(fill no)
			(layer "F.CrtYd")
		)
		(fp_rect
			(start -0.4318 0.9525)
			(end 0.4318 -0.9525)
			(stroke
				(width 0)
				(type default)
			)
			(fill no)
			(layer "F.Fab")
		)
		(pad "1" smd custom
			(at 0 -0.4445 270)
			(size 0.1524 0.1524)
			(layers "F.Cu" "F.Mask" "F.Paste")
			(net "SW_HDD_P9")
			(options
				(clearance outline)
				(anchor circle)
			)
			(primitives
				(gr_poly
					(pts
						(arc
							(start 0.3048 -0.2032)
							(mid 0.275042 -0.275042)
							(end 0.2032 -0.3048)
						)
						(arc
							(start -0.2032 -0.3048)
							(mid -0.275042 -0.275042)
							(end -0.3048 -0.2032)
						)
						(arc
							(start -0.3048 0.2032)
							(mid -0.275042 0.275042)
							(end -0.2032 0.3048)
						)
						(arc
							(start 0.2032 0.3048)
							(mid 0.275042 0.275042)
							(end 0.3048 0.2032)
						)
					)
					(width 0)
					(fill yes)
				)
			)
		)
		(pad "2" smd custom
			(at 0 0.4445 270)
			(size 0.1524 0.1524)
			(layers "F.Cu" "F.Mask" "F.Paste")
			(net "GND")
			(options
				(clearance outline)
				(anchor circle)
			)
			(primitives
				(gr_poly
					(pts
						(arc
							(start 0.3048 -0.2032)
							(mid 0.275042 -0.275042)
							(end 0.2032 -0.3048)
						)
						(arc
							(start -0.2032 -0.3048)
							(mid -0.275042 -0.275042)
							(end -0.3048 -0.2032)
						)
						(arc
							(start -0.3048 0.2032)
							(mid -0.275042 0.275042)
							(end -0.2032 0.3048)
						)
						(arc
							(start 0.2032 0.3048)
							(mid 0.275042 0.275042)
							(end 0.3048 0.2032)
						)
					)
					(width 0)
					(fill yes)
				)
			)
		)
	)
	(footprint ""
		(layer "F.Cu")
		(at 340.251796 -97.390204 -90)
		(property "Reference" "R472"
			(at 0 0 270)
			(layer "F.SilkS")
			(hide yes)
			(effects
				(font
					(size 1.27 1.27)
				)
			)
		)
		(property "Value" "4K7R2F-GP"
			(at 0.064008 -3.993896 270)
			(unlocked yes)
			(layer "F.Fab")
			(hide yes)
			(effects
				(font
					(size 1.016 1.016)
					(thickness 0.1524)
				)
			)
		)
		(property "Device Type" "R402H16"
			(at 0.064008 -5.517896 270)
			(unlocked yes)
			(layer "F.Fab")
			(hide yes)
			(effects
				(font
					(size 1.016 1.016)
					(thickness 0.1524)
				)
			)
		)
		(duplicate_pad_numbers_are_jumpers no)
		(fp_line
			(start -0.508 -0.9398)
			(end -0.508 0.9398)
			(stroke
				(width 0.1524)
				(type default)
			)
			(layer "F.SilkS")
		)
		(fp_line
			(start 0.508 -0.9398)
			(end -0.508 -0.9398)
			(stroke
				(width 0.1524)
				(type default)
			)
			(layer "F.SilkS")
		)
		(fp_rect
			(start -0.508 0.9398)
			(end 0.508 -0.9398)
			(stroke
				(width 0)
				(type default)
			)
			(fill no)
			(layer "F.CrtYd")
		)
		(fp_rect
			(start -0.508 0.9398)
			(end 0.508 -0.9398)
			(stroke
				(width 0)
				(type default)
			)
			(fill no)
			(layer "F.Fab")
		)
		(pad "1" smd custom
			(at 0 -0.4445 270)
			(size 0.1397 0.1397)
			(layers "F.Cu" "F.Mask" "F.Paste")
			(net "DRIVE_B_19_ACT")
			(options
				(clearance outline)
				(anchor circle)
			)
			(primitives
				(gr_poly
					(pts
						(arc
							(start -0.1778 -0.2794)
							(mid -0.249642 -0.249642)
							(end -0.2794 -0.1778)
						)
						(arc
							(start -0.2794 0.1778)
							(mid -0.249642 0.249642)
							(end -0.1778 0.2794)
						)
						(arc
							(start 0.1778 0.2794)
							(mid 0.249642 0.249642)
							(end 0.2794 0.1778)
						)
						(arc
							(start 0.2794 -0.1778)
							(mid 0.249642 -0.249642)
							(end 0.1778 -0.2794)
						)
					)
					(width 0)
					(fill yes)
				)
			)
		)
		(pad "2" smd custom
			(at 0 0.4445 270)
			(size 0.1397 0.1397)
			(layers "F.Cu" "F.Mask" "F.Paste")
			(net "GND")
			(options
				(clearance outline)
				(anchor circle)
			)
			(primitives
				(gr_poly
					(pts
						(arc
							(start -0.1778 -0.2794)
							(mid -0.249642 -0.249642)
							(end -0.2794 -0.1778)
						)
						(arc
							(start -0.2794 0.1778)
							(mid -0.249642 0.249642)
							(end -0.1778 0.2794)
						)
						(arc
							(start 0.1778 0.2794)
							(mid 0.249642 0.249642)
							(end 0.2794 0.1778)
						)
						(arc
							(start 0.2794 -0.1778)
							(mid 0.249642 -0.249642)
							(end 0.1778 -0.2794)
						)
					)
					(width 0)
					(fill yes)
				)
			)
		)
	)
)
